# BASEBOARD_FAB2 (Tioga Pass) — schematic netlist excerpt (pin names and nets, part order shuffled) for the footprints in the layout excerpt that follows; sources: Cadence DE-HDL packaged netlist, KiCad conversion of Wiwynn_Tioga_Pass_MB.brd

J4G1  SCONN288_H44441004  SCONN  pkg PIP  page 43
  \12v\(1)  = P12V_NVDIMM_ABC
  VSS(93)  = GND
  DQ(4)  = M_A_DQ<5>
  VSS(92)  = GND
  DQ(0)  = M_A_DQ<1>
  VSS(91)  = GND
  DQS9P  = M_A_DQS_DP<9>
  DQS9N  = M_A_DQS_DN<9>
  VSS(90)  = GND
  DQ(6)  = M_A_DQ<7>
  VSS(89)  = GND
  DQ(2)  = M_A_DQ<3>
  VSS(88)  = GND
  DQ(12)  = M_A_DQ<13>
  VSS(87)  = GND
  DQ(8)  = M_A_DQ<9>
  VSS(86)  = GND
  DQS10P  = M_A_DQS_DP<10>
  DQS10N  = M_A_DQS_DN<10>
  VSS(85)  = GND
  DQ(14)  = M_A_DQ<15>
  VSS(84)  = GND
  DQ(10)  = M_A_DQ<11>
  VSS(83)  = GND
  DQ(20)  = M_A_DQ<21>
  VSS(82)  = GND
  DQ(16)  = M_A_DQ<17>
  VSS(81)  = GND
  DQS11P  = M_A_DQS_DP<11>
  DQS11N  = M_A_DQS_DN<11>
  VSS(80)  = GND
  DQ(22)  = M_A_DQ<23>
  VSS(79)  = GND
  DQ(18)  = M_A_DQ<19>
  VSS(78)  = GND
  DQ(28)  = M_A_DQ<29>
  VSS(77)  = GND
  DQ(24)  = M_A_DQ<25>
  VSS(76)  = GND
  DQS12P  = M_A_DQS_DP<12>
  DQS12N  = M_A_DQS_DN<12>
  VSS(75)  = GND
  DQ(30)  = M_A_DQ<31>
  VSS(74)  = GND
  DQ(26)  = M_A_DQ<27>
  VSS(73)  = GND
  CB(4)  = M_A_ECC<5>
  VSS(72)  = GND
  CB(0)  = M_A_ECC<1>
  VSS(71)  = GND
  DQS17P  = M_A_DQS_DP<17>
  DQS17N  = M_A_DQS_DN<17>
  VSS(70)  = GND
  CB(6)  = M_A_ECC<7>
  VSS(69)  = GND
  CB(2)  = M_A_ECC<3>
  VSS(68)  = GND
  RESET_N  = M_ABC_RST_N
  VDD(25)  = PVDDQ_ABC
  CKE(0)  = M_A_CKE<0>
  VDD(24)  = PVDDQ_ABC
  ACT_N  = M_A_ACT_N
  BG(0)  = M_A_BG<0>
  VDD(23)  = PVDDQ_ABC
  A12  = M_A_MA<12>
  A9  = M_A_MA<9>
  VDD(22)  = PVDDQ_ABC
  A8  = M_A_MA<8>
  A6  = M_A_MA<6>
  VDD(21)  = PVDDQ_ABC
  A3  = M_A_MA<3>
  A1  = M_A_MA<1>
  VDD(20)  = PVDDQ_ABC
  CK0P  = M_A_CLK_DP<0>
  CK0N  = M_A_CLK_DN<0>
  VDD(19)  = PVDDQ_ABC
  VTT(1)  = PVTT_ABC
  EVENT_N  = FM_DIMM_EVENT_COD_N
  A0  = M_A_MA<0>
  VDD(18)  = PVDDQ_ABC
  BA(0)  = M_A_BA<0>
  A16_RAS_N  = M_A_MA<16>
  VDD(17)  = PVDDQ_ABC
  S0_N  = M_A_CS_N<0>
  VDD(16)  = PVDDQ_ABC
  A15_CAS_N  = M_A_MA<15>
  ODT(0)  = M_A_ODT<0>
  VDD(15)  = PVDDQ_ABC
  S1_N  = M_A_CS_N<1>
  VDD(14)  = PVDDQ_ABC
  ODT(1)  = M_A_ODT<1>
  VDD(13)  = PVDDQ_ABC
  S2_N_C(0)  = M_A_CS_N<2>
  VSS(67)  = GND
  DQ(36)  = M_A_DQ<37>
  VSS(66)  = GND
  DQ(32)  = M_A_DQ<33>
  VSS(65)  = GND
  DQS13P  = M_A_DQS_DP<13>
  DQS13N  = M_A_DQS_DN<13>
  VSS(64)  = GND
  DQ(38)  = M_A_DQ<39>
  VSS(63)  = GND
  DQ(34)  = M_A_DQ<35>
  VSS(62)  = GND
  DQ(44)  = M_A_DQ<45>
  VSS(61)  = GND
  DQ(40)  = M_A_DQ<41>
  VSS(60)  = GND
  DQS14P  = M_A_DQS_DP<14>
  DQS14N  = M_A_DQS_DN<14>
  VSS(59)  = GND
  DQ(46)  = M_A_DQ<47>
  VSS(58)  = GND
  DQ(42)  = M_A_DQ<43>
  VSS(57)  = GND
  DQ(52)  = M_A_DQ<53>
  VSS(56)  = GND
  DQ(48)  = M_A_DQ<49>
  VSS(55)  = GND
  DQS15P  = M_A_DQS_DP<15>
  DQS15N  = M_A_DQS_DN<15>
  VSS(54)  = GND
  DQ(54)  = M_A_DQ<55>
  VSS(53)  = GND
  DQ(50)  = M_A_DQ<51>
  VSS(52)  = GND
  DQ(60)  = M_A_DQ<61>
  VSS(51)  = GND
  DQ(56)  = M_A_DQ<57>
  VSS(50)  = GND
  DQS16P  = M_A_DQS_DP<16>
  DQS16N  = M_A_DQS_DN<16>
  VSS(49)  = GND
  DQ(62)  = M_A_DQ<63>
  VSS(48)  = GND
  DQ(58)  = M_A_DQ<59>
  VSS(47)  = GND
  SA(0)  = GND
  SA(1)  = GND
  SCL  = SMB_DDR_ABC_VPP_SCL
  VPP(4)  = PVPP_ABC
  VPP(3)  = PVPP_ABC
  RFU(2)  = TP_CH_A_DIMM_A0_RFU_2
  \12v\(0)  = P12V_NVDIMM_ABC
  VREFCA  = M_A_VREF
  VSS(46)  = GND
  DQ(5)  = M_A_DQ<4>
  VSS(45)  = GND
  DQ(1)  = M_A_DQ<0>
  VSS(44)  = GND
  DQS0N  = M_A_DQS_DN<0>
  DQS0P  = M_A_DQS_DP<0>
  VSS(43)  = GND
  DQ(7)  = M_A_DQ<6>
  VSS(42)  = GND
  DQ(3)  = M_A_DQ<2>
  VSS(41)  = GND
  DQ(13)  = M_A_DQ<12>
  VSS(40)  = GND
  DQ(9)  = M_A_DQ<8>
  VSS(39)  = GND
  DQS1N  = M_A_DQS_DN<1>
  DQS1P  = M_A_DQS_DP<1>
  VSS(38)  = GND
  DQ(15)  = M_A_DQ<14>
  VSS(37)  = GND
  DQ(11)  = M_A_DQ<10>
  VSS(36)  = GND
  DQ(21)  = M_A_DQ<20>
  VSS(35)  = GND
  DQ(17)  = M_A_DQ<16>
  VSS(34)  = GND
  DQS2N  = M_A_DQS_DN<2>
  DQS2P  = M_A_DQS_DP<2>
  VSS(33)  = GND
  DQ(23)  = M_A_DQ<22>
  VSS(32)  = GND
  DQ(19)  = M_A_DQ<18>
  VSS(31)  = GND
  DQ(29)  = M_A_DQ<28>
  VSS(30)  = GND
  DQ(25)  = M_A_DQ<24>
  VSS(29)  = GND
  DQS3N  = M_A_DQS_DN<3>
  DQS3P  = M_A_DQS_DP<3>
  VSS(28)  = GND
  DQ(31)  = M_A_DQ<30>
  VSS(27)  = GND
  DQ(27)  = M_A_DQ<26>
  VSS(26)  = GND
  CB(5)  = M_A_ECC<4>
  VSS(25)  = GND
  CB(1)  = M_A_ECC<0>
  VSS(24)  = GND
  DQS8N  = M_A_DQS_DN<8>
  DQS8P  = M_A_DQS_DP<8>
  VSS(23)  = GND
  CB(7)  = M_A_ECC<6>
  VSS(22)  = GND
  CB(3)  = M_A_ECC<2>
  VSS(21)  = GND
  CKE(1)  = M_A_CKE<1>
  VDD(12)  = PVDDQ_ABC
  RFU(0)  = TP_CH_A_DIMM_A0_RFU_0
  VDD(11)  = PVDDQ_ABC
  BG(1)  = M_A_BG<1>
  ALERT_N  = M_A_ALERT_N
  VDD(10)  = PVDDQ_ABC
  A11  = M_A_MA<11>
  A7  = M_A_MA<7>
  VDD(9)  = PVDDQ_ABC
  A5  = M_A_MA<5>
  A4  = M_A_MA<4>
  VDD(8)  = PVDDQ_ABC
  A2  = M_A_MA<2>
  VDD(7)  = PVDDQ_ABC
  CK1P  = M_A_CLK_DP<1>
  CK1N  = M_A_CLK_DN<1>
  VDD(6)  = PVDDQ_ABC
  VTT(0)  = PVTT_ABC
  PAR  = M_A_PAR
  VDD(5)  = PVDDQ_ABC
  BA(1)  = M_A_BA<1>
  A10  = M_A_MA<10>
  VDD(4)  = PVDDQ_ABC
  RFU(1)  = TP_CH_A_DIMM_A0_RFU_1
  A14_WE_N  = M_A_MA<14>
  VDD(3)  = PVDDQ_ABC
  SAVE_N_NC  = FM_ADR_COMPLETE_ABC_N
  VDD(2)  = PVDDQ_ABC
  A13  = M_A_MA<13>
  VDD(1)  = PVDDQ_ABC
  A17  = M_A_MA<17>
  C(2)  = M_A_C<2>
  VDD(0)  = PVDDQ_ABC
  S3_N_C(1)  = M_A_CS_N<3>
  SA(2)  = GND
  VSS(20)  = GND
  DQ(37)  = M_A_DQ<36>
  VSS(19)  = GND
  DQ(33)  = M_A_DQ<32>
  VSS(18)  = GND
  DQS4N  = M_A_DQS_DN<4>
  DQS4P  = M_A_DQS_DP<4>
  VSS(17)  = GND
  DQ(39)  = M_A_DQ<38>
  VSS(16)  = GND
  DQ(35)  = M_A_DQ<34>
  VSS(15)  = GND
  DQ(45)  = M_A_DQ<44>
  VSS(14)  = GND
  DQ(41)  = M_A_DQ<40>
  VSS(13)  = GND
  DQS5N  = M_A_DQS_DN<5>
  DQS5P  = M_A_DQS_DP<5>
  VSS(12)  = GND
  DQ(47)  = M_A_DQ<46>
  VSS(11)  = GND
  DQ(43)  = M_A_DQ<42>
  VSS(10)  = GND
  DQ(53)  = M_A_DQ<52>
  VSS(9)  = GND
  DQ(49)  = M_A_DQ<48>
  VSS(8)  = GND
  DQS6N  = M_A_DQS_DN<6>
  DQS6P  = M_A_DQS_DP<6>
  VSS(7)  = GND
  DQ(55)  = M_A_DQ<54>
  VSS(6)  = GND
  DQ(51)  = M_A_DQ<50>
  VSS(5)  = GND
  DQ(61)  = M_A_DQ<60>
  VSS(4)  = GND
  DQ(57)  = M_A_DQ<56>
  VSS(3)  = GND
  DQS7N  = M_A_DQS_DN<7>
  DQS7P  = M_A_DQS_DP<7>
  VSS(2)  = GND
  DQ(63)  = M_A_DQ<62>
  VSS(1)  = GND
  DQ(59)  = M_A_DQ<58>
  VSS(0)  = GND
  VDDSPD  = PVPP_ABC
  SDA  = SMB_DDR_ABC_VPP_SDA
  VPP(1)  = PVPP_ABC
  VPP(0)  = PVPP_ABC
  VPP(2)  = PVPP_ABC

(kicad_pcb
	(version 20260206)
	(generator "pcbnew")
	(generator_version "10.0")
	(general
		(thickness 1.6)
		(legacy_teardrops no)
	)
	(paper "A4")
	(title_block
		(title "Wiwynn_Tioga_Pass_MB.brd")
		(comment 1 "Tioga Pass / footprint 2167 of 4770 (J4G1), pads 52-101 of 291")
	)
	(layers
		(0 "F.Cu" signal "TOP")
		(4 "In1.Cu" signal "L2GND")
		(6 "In2.Cu" signal "L3")
		(8 "In3.Cu" signal "L4GND")
		(10 "In4.Cu" signal "L5")
		(12 "In5.Cu" signal "L6GND")
		(14 "In6.Cu" signal "L7VCC")
		(16 "In7.Cu" signal "L8VCC")
		(18 "In8.Cu" signal "L9GND")
		(20 "In9.Cu" signal "L10")
		(22 "In10.Cu" signal "L11GND")
		(24 "In11.Cu" signal "L12")
		(26 "In12.Cu" signal "L13GND")
		(2 "B.Cu" signal "BOTTOM")
		(9 "F.Adhes" user "F.Adhesive")
		(11 "B.Adhes" user "B.Adhesive")
		(13 "F.Paste" user "Package Geometry/Pastemask Top")
		(15 "B.Paste" user "Package Geometry/Pastemask Bottom")
		(5 "F.SilkS" user "Ref Des/Silkscreen Top")
		(7 "B.SilkS" user "Ref Des/Silkscreen Bottom")
		(1 "F.Mask" user "Board Geometry/Soldermask Top")
		(3 "B.Mask" user "Board Geometry/Soldermask Bottom")
		(17 "Dwgs.User" user "User.Drawings")
		(19 "Cmts.User" user "User.Comments")
		(21 "Eco1.User" user "User.Eco1")
		(23 "Eco2.User" user "User.Eco2")
		(25 "Edge.Cuts" user "Board Geometry/Outline")
		(27 "Margin" user)
		(31 "F.CrtYd" user "Package Geometry/Place Bound Top")
		(29 "B.CrtYd" user "Package Geometry/Place Bound Bottom")
		(35 "F.Fab" user "Ref Des/Assembly Top")
		(33 "B.Fab" user "Ref Des/Assembly Bottom")
	)
	(footprint ""
		(layer "F.Cu")
		(at 194.700398 -15.423642 90)
		(property "Reference" "J4G1"
			(at 9.060688 37.32911 0)
			(unlocked yes)
			(layer "F.SilkS")
			(effects
				(font
					(size 0.7874 0.5842)
					(thickness 0.1524)
				)
				(justify left)
			)
		)
		(property "Value" ""
			(at 0 0 90)
			(layer "F.Fab")
			(effects
				(font
					(size 1.27 1.27)
				)
			)
		)
		(duplicate_pad_numbers_are_jumpers no)
		(pad "49" smd rect
			(at 0 40.80002 90)
			(size 1.8034 0.508)
			(layers "F.Cu" "F.Mask" "F.Paste")
			(net "M_A_ECC<1>")
		)
		(pad "50" smd rect
			(at 0 41.649904 90)
			(size 1.8034 0.508)
			(layers "F.Cu" "F.Mask" "F.Paste")
			(net "GND")
		)
		(pad "51" smd rect
			(at 0 42.500042 90)
			(size 1.8034 0.508)
			(layers "F.Cu" "F.Mask" "F.Paste")
			(net "M_A_DQS_DP<17>")
		)
		(pad "52" smd rect
			(at 0 43.349926 90)
			(size 1.8034 0.508)
			(layers "F.Cu" "F.Mask" "F.Paste")
			(net "M_A_DQS_DN<17>")
		)
		(pad "53" smd rect
			(at 0 44.200064 90)
			(size 1.8034 0.508)
			(layers "F.Cu" "F.Mask" "F.Paste")
			(net "GND")
		)
		(pad "54" smd rect
			(at 0 45.049948 90)
			(size 1.8034 0.508)
			(layers "F.Cu" "F.Mask" "F.Paste")
			(net "M_A_ECC<7>")
		)
		(pad "55" smd rect
			(at 0 45.900086 90)
			(size 1.8034 0.508)
			(layers "F.Cu" "F.Mask" "F.Paste")
			(net "GND")
		)
		(pad "56" smd rect
			(at 0 46.74997 90)
			(size 1.8034 0.508)
			(layers "F.Cu" "F.Mask" "F.Paste")
			(net "M_A_ECC<3>")
		)
		(pad "57" smd rect
			(at 0 47.600108 90)
			(size 1.8034 0.508)
			(layers "F.Cu" "F.Mask" "F.Paste")
			(net "GND")
		)
		(pad "58" smd rect
			(at 0 48.449992 90)
			(size 1.8034 0.508)
			(layers "F.Cu" "F.Mask" "F.Paste")
			(net "M_ABC_RST_N")
		)
		(pad "59" smd rect
			(at 0 49.299876 90)
			(size 1.8034 0.508)
			(layers "F.Cu" "F.Mask" "F.Paste")
			(net "PVDDQ_ABC")
		)
		(pad "60" smd rect
			(at 0 50.150014 90)
			(size 1.8034 0.508)
			(layers "F.Cu" "F.Mask" "F.Paste")
			(net "M_A_CKE<0>")
		)
		(pad "61" smd rect
			(at 0 50.999898 90)
			(size 1.8034 0.508)
			(layers "F.Cu" "F.Mask" "F.Paste")
			(net "PVDDQ_ABC")
		)
		(pad "62" smd rect
			(at 0 51.850036 90)
			(size 1.8034 0.508)
			(layers "F.Cu" "F.Mask" "F.Paste")
			(net "M_A_ACT_N")
		)
		(pad "63" smd rect
			(at 0 52.69992 90)
			(size 1.8034 0.508)
			(layers "F.Cu" "F.Mask" "F.Paste")
			(net "M_A_BG<0>")
		)
		(pad "64" smd rect
			(at 0 53.550058 90)
			(size 1.8034 0.508)
			(layers "F.Cu" "F.Mask" "F.Paste")
			(net "PVDDQ_ABC")
		)
		(pad "65" smd rect
			(at 0 54.399942 90)
			(size 1.8034 0.508)
			(layers "F.Cu" "F.Mask" "F.Paste")
			(net "M_A_MA<12>")
		)
		(pad "66" smd rect
			(at 0 55.25008 90)
			(size 1.8034 0.508)
			(layers "F.Cu" "F.Mask" "F.Paste")
			(net "M_A_MA<9>")
		)
		(pad "67" smd rect
			(at 0 56.099964 90)
			(size 1.8034 0.508)
			(layers "F.Cu" "F.Mask" "F.Paste")
			(net "PVDDQ_ABC")
		)
		(pad "68" smd rect
			(at 0 56.950102 90)
			(size 1.8034 0.508)
			(layers "F.Cu" "F.Mask" "F.Paste")
			(net "M_A_MA<8>")
		)
		(pad "69" smd rect
			(at 0 57.799986 90)
			(size 1.8034 0.508)
			(layers "F.Cu" "F.Mask" "F.Paste")
			(net "M_A_MA<6>")
		)
		(pad "70" smd rect
			(at 0 58.650124 90)
			(size 1.8034 0.508)
			(layers "F.Cu" "F.Mask" "F.Paste")
			(net "PVDDQ_ABC")
		)
		(pad "71" smd rect
			(at 0 59.500008 90)
			(size 1.8034 0.508)
			(layers "F.Cu" "F.Mask" "F.Paste")
			(net "M_A_MA<3>")
		)
		(pad "72" smd rect
			(at 0 60.349892 90)
			(size 1.8034 0.508)
			(layers "F.Cu" "F.Mask" "F.Paste")
			(net "M_A_MA<1>")
		)
		(pad "73" smd rect
			(at 0 61.20003 90)
			(size 1.8034 0.508)
			(layers "F.Cu" "F.Mask" "F.Paste")
			(net "PVDDQ_ABC")
		)
		(pad "74" smd rect
			(at 0 62.049914 90)
			(size 1.8034 0.508)
			(layers "F.Cu" "F.Mask" "F.Paste")
			(net "M_A_CLK_DP<0>")
		)
		(pad "75" smd rect
			(at 0 62.900052 90)
			(size 1.8034 0.508)
			(layers "F.Cu" "F.Mask" "F.Paste")
			(net "M_A_CLK_DN<0>")
		)
		(pad "76" smd rect
			(at 0 63.749936 90)
			(size 1.8034 0.508)
			(layers "F.Cu" "F.Mask" "F.Paste")
			(net "PVDDQ_ABC")
		)
		(pad "77" smd rect
			(at 0 64.600074 90)
			(size 1.8034 0.508)
			(layers "F.Cu" "F.Mask" "F.Paste")
			(net "PVTT_ABC")
		)
		(pad "78" smd rect
			(at 0 70.550024 90)
			(size 1.8034 0.508)
			(layers "F.Cu" "F.Mask" "F.Paste")
			(net "FM_DIMM_EVENT_COD_N")
		)
		(pad "79" smd rect
			(at 0 71.399908 90)
			(size 1.8034 0.508)
			(layers "F.Cu" "F.Mask" "F.Paste")
			(net "M_A_MA<0>")
		)
		(pad "80" smd rect
			(at 0 72.250046 90)
			(size 1.8034 0.508)
			(layers "F.Cu" "F.Mask" "F.Paste")
			(net "PVDDQ_ABC")
		)
		(pad "81" smd rect
			(at 0 73.09993 90)
			(size 1.8034 0.508)
			(layers "F.Cu" "F.Mask" "F.Paste")
			(net "M_A_BA<0>")
		)
		(pad "82" smd rect
			(at 0 73.950068 90)
			(size 1.8034 0.508)
			(layers "F.Cu" "F.Mask" "F.Paste")
			(net "M_A_MA<16>")
		)
		(pad "83" smd rect
			(at 0 74.799952 90)
			(size 1.8034 0.508)
			(layers "F.Cu" "F.Mask" "F.Paste")
			(net "PVDDQ_ABC")
		)
		(pad "84" smd rect
			(at 0 75.65009 90)
			(size 1.8034 0.508)
			(layers "F.Cu" "F.Mask" "F.Paste")
			(net "M_A_CS_N<0>")
		)
		(pad "85" smd rect
			(at 0 76.499974 90)
			(size 1.8034 0.508)
			(layers "F.Cu" "F.Mask" "F.Paste")
			(net "PVDDQ_ABC")
		)
		(pad "86" smd rect
			(at 0 77.350112 90)
			(size 1.8034 0.508)
			(layers "F.Cu" "F.Mask" "F.Paste")
			(net "M_A_MA<15>")
		)
		(pad "87" smd rect
			(at 0 78.199996 90)
			(size 1.8034 0.508)
			(layers "F.Cu" "F.Mask" "F.Paste")
			(net "M_A_ODT<0>")
		)
		(pad "88" smd rect
			(at 0 79.04988 90)
			(size 1.8034 0.508)
			(layers "F.Cu" "F.Mask" "F.Paste")
			(net "PVDDQ_ABC")
		)
		(pad "89" smd rect
			(at 0 79.900018 90)
			(size 1.8034 0.508)
			(layers "F.Cu" "F.Mask" "F.Paste")
			(net "M_A_CS_N<1>")
		)
		(pad "90" smd rect
			(at 0 80.749902 90)
			(size 1.8034 0.508)
			(layers "F.Cu" "F.Mask" "F.Paste")
			(net "PVDDQ_ABC")
		)
		(pad "91" smd rect
			(at 0 81.60004 90)
			(size 1.8034 0.508)
			(layers "F.Cu" "F.Mask" "F.Paste")
			(net "M_A_ODT<1>")
		)
		(pad "92" smd rect
			(at 0 82.449924 90)
			(size 1.8034 0.508)
			(layers "F.Cu" "F.Mask" "F.Paste")
			(net "PVDDQ_ABC")
		)
		(pad "93" smd rect
			(at 0 83.300062 90)
			(size 1.8034 0.508)
			(layers "F.Cu" "F.Mask" "F.Paste")
			(net "M_A_CS_N<2>")
		)
		(pad "94" smd rect
			(at 0 84.149946 90)
			(size 1.8034 0.508)
			(layers "F.Cu" "F.Mask" "F.Paste")
			(net "GND")
		)
		(pad "95" smd rect
			(at 0 85.000084 90)
			(size 1.8034 0.508)
			(layers "F.Cu" "F.Mask" "F.Paste")
			(net "M_A_DQ<37>")
		)
		(pad "96" smd rect
			(at 0 85.849968 90)
			(size 1.8034 0.508)
			(layers "F.Cu" "F.Mask" "F.Paste")
			(net "GND")
		)
		(pad "97" smd rect
			(at 0 86.700106 90)
			(size 1.8034 0.508)
			(layers "F.Cu" "F.Mask" "F.Paste")
			(net "M_A_DQ<33>")
		)
		(pad "98" smd rect
			(at 0 87.54999 90)
			(size 1.8034 0.508)
			(layers "F.Cu" "F.Mask" "F.Paste")
			(net "GND")
		)
	)
)
